# BASEBOARD_FAB2 (Tioga Pass) — schematic parts with pin connectivity, parts 4676–4688 of 4751; source: Cadence DE-HDL packaged netlist (pstxprt.dat, pstxnet.dat, pstchip.dat)

U7C1  LBG_CORE_QAT_EXT_D  IC  pkg BGA1  page 114  (pins 1249-1310 of 1310)
  V15  THRMTRIP_N  BI  = FM_PCH_LVC1_THERMTRIP_N
  V18  HDA_SDI_1  BI  = TP_PCH_HDA_SDI_1
  V22  RSVD(68)  BI  = TP_PCH_DISPA_SDO
  V26  VSS(320)  GROUND  = GND
  V29  VCCPRIM_AVID(58)  POWER  = PVNN_PCH_STBY
  V33  VCCPRIM_AVID(57)  POWER  = PVNN_PCH_STBY
  V37  VCCPRIM_AVID_QAT_SENSE  UNSPEC  = VSENSE_PVNN_PCH_STBY_QAT
  V40  VCCPRIM_AVID(56)  POWER  = PVNN_PCH_STBY
  V44  VCCPRIM_1P05(12)  POWER  = P1V05_PCH_STBY
  V48  VSS(319)  GROUND  = GND
  V52  VSS(317)  GROUND  = GND
  V56  RSVD(33)  UNSPEC  = TP_PCH_RSVD33
  V59  PCIEUP_11_TXP  BI  = P3E_CPU0_PE1_PCH_R_RXP<11>
  V63  PCIEUP_14_TXP  BI  = P3E_CPU0_PE1_PCH_R_RXP<14>
  V66  VSS(315)  GROUND  = GND
  V68  VSS(314)  GROUND  = GND
  V70  PCIE13_UP1_SATA1_TXN  BI  = SATA6G_PCH_PCIE_UP_SATA_TXN<1>
  V72  PCIE13_UP1_SATA1_TXP  BI  = SATA6G_PCH_PCIE_UP_SATA_TXP<1>
  W2  GPP_A3_LAD2_ESPI_IO2  BI  = LPC_LAD2_IO2
  W4  GPP_A20  BI  = NC
  W9  VSS(306)  GROUND  = GND
  W13  VSS(313)  GROUND  = GND
  W17  VSS(312)  GROUND  = GND
  W20  VSS(311)  GROUND  = GND
  W24  VSS(310)  GROUND  = GND
  W50  VCCA_CLKFILT_1P05(0)  POWER  = P1V05_PCH_STBY_ISCLK_PLL
  W54  RSVD(35)  UNSPEC  = TP_PCH_RSVD35
  W58  VSS(316)  GROUND  = GND
  W61  VSS(307)  GROUND  = GND
  W65  PCIEUP_14_TXN  BI  = P3E_CPU0_PE1_PCH_R_RXN<14>
  W69  PCIE12_UP0_SATA0_TXN  BI  = SATA6G_PCH_PCIE_UP_SATA_TXN<0>
  W71  PCIE12_UP0_SATA0_TXP  BI  = SATA6G_PCH_PCIE_UP_SATA_TXP<0>
  Y1  GPP_A4_LAD3_ESPI_IO3  BI  = LPC_LAD3_IO3
  Y3  GPP_A1_LAD0_ESPI_IO0  BI  = LPC_LAD0_IO0
  Y5  VSS(302)  GROUND  = GND
  Y7  GPP_L16_TESTCH1_D5  BI  = FM_CPU0_PROCHOT_PCH_N
  Y11  GPP_L15_TESTCH1_D4  BI  = H_CPU1_MEMKLM_MEMHOT_PCH_N
  Y15  GPP_L12_TESTCH1_D1  BI  = H_CPU0_MEMABC_MEMHOT_PCH_N
  Y18  GPP_L5_TESTCH0_D3  BI  = FM_PRSNT_2_4_N
  Y22  VSS(305)  GROUND  = GND
  Y26  VCCPRIM_1P05(19)  POWER  = P1V05_PCH_STBY
  Y27  VSS(304)  GROUND  = GND
  Y29  VCCPRIM_AVID(55)  POWER  = PVNN_PCH_STBY
  Y30  VCCPRIM_AVID(54)  POWER  = PVNN_PCH_STBY
  Y32  VCCPRIM_AVID(53)  POWER  = PVNN_PCH_STBY
  Y34  VCCPRIM_AVID(52)  POWER  = PVNN_PCH_STBY
  Y36  VCCPRIM_AVID(51)  POWER  = PVNN_PCH_STBY
  Y37  VCCPRIM_AVID(50)  POWER  = PVNN_PCH_STBY
  Y39  VCCPRIM_AVID(49)  POWER  = PVNN_PCH_STBY
  Y41  VCCPRIM_AVID(48)  POWER  = PVNN_PCH_STBY
  Y43  VSS(308)  GROUND  = GND
  Y45  VCCPRIM_1P05(11)  POWER  = P1V05_PCH_STBY
  Y46  VCCPRIM_1P05(10)  POWER  = P1V05_PCH_STBY
  Y48  VSS(303)  GROUND  = GND
  Y52  VSS(301)  GROUND  = GND
  Y56  RSVD(34)  UNSPEC  = TP_PCH_RSVD34
  Y59  VSS(300)  GROUND  = GND
  Y63  VSS(299)  GROUND  = GND
  Y66  PCIEUP_15_TXN  BI  = P3E_CPU0_PE1_PCH_R_RXN<15>
  Y68  VSS(298)  GROUND  = GND
  Y70  VSS(449)  GROUND  = GND
  Y72  VSS(450)  GROUND  = GND

U7D1  74CBTLV1G125  IC  pkg SMLF  page 118
  1  OE_N  IN  = PWRGD_PVCCIO_CPU0
  2  A  IN  = XDP_PCH_PWR_DEBUG_N
  4  B  OUT  = XDP_CPU_PWR_DEBUG_N

U7D2  GTL2014  IC  pkg SM  page 92
  1  DIR  IN  = PD_GTL2104_DIR_0
  2  B0  BI  = H_CPU_MSMI_G_N
  3  B1  BI  = H_CPU0_FIVR_FAULT_G
  4  VREF  POWER  = P0V7_GTL2104_VREF_0
  5  B2  BI  = H_CPU_ERR2_GTL_N
  6  B3  BI  = H_CPU0_THERMTRIP_G_N
  7  GND(0)  GROUND  = GND
  8  GND(1)  GROUND  = GND
  9  A3  BI  = FM_CPU0_THERMTRIP_LVT3_R_N
  10  A2  BI  = FM_CPU_ERR2_LVT3_R_N
  11  GND(2)  GROUND  = GND
  12  A1  BI  = FM_CPU0_FIVR_FAULT_R_LVT3
  13  A0  BI  = FM_CPU_MSMI_LVT3_R_N
  14  VCC  POWER  = P3V3

U7D3  ADM1085  IC  pkg SMT  page 196
  1  ENIN  IN  = PWRGD_P3V3_STBY
  2  GND  GROUND  = GND
  3  VIN  IN  = VSENSE_P12V_ADM1085
  4  ENOUT  OUT  = PWRGD_DSW_PWROK
  5  CEXT  UNSPEC  = A_ADM1085_CEXT
  6  VCC  POWER  = P3V3_STBY

U7E1  PCA9617  IC  pkg SSOP  page 99
  1  VCCA  POWER  = PVCCIO_CPU0
  2  SCLA  IN  = SMB_DDR_DEF_SCL_G
  3  SDAA  IN  = SMB_DDR_DEF_SDA_G
  5  EN  IN  = TP_SMB_DDR_DEF_EN
  6  SDAB  OUT  = SMB_DDR_DEF_VPP_SDA_R
  7  SCLB  OUT  = SMB_DDR_DEF_VPP_SCL_R
  8  VCCB  POWER  = PVPP_DEF

U7E2  TTL1G08  NC7SZ08 IC  pkg SOTLF  page 95
  1  A(0)  IN  = FM_PVCCIN_CPU0_PWR_IN_ALERT_N
  2  B(0)  IN  = IRQ_PVCCIN_CPU0_VRHOT_LVC3_N
  4  Y(0)  OUT  = IRQ_CPU0_PROCHOT_G_N

U7E3  TTL1G08  NC7SZ08 IC  pkg SOTLF  page 95
  1  A(0)  IN  = FM_PVCCIN_CPU1_PWR_IN_ALERT_N
  2  B(0)  IN  = IRQ_PVCCIN_CPU1_VRHOT_LVC3_N
  4  Y(0)  OUT  = IRQ_CPU1_PROCHOT_G_N

U7F1  W25Q256  IC  pkg XSOI  page 153
  1  HOLD_N_IO(3)  BI  = PU_BIOS_SPI_HOLD0_N
  2  VCC  POWER  = P3V3_STBY
  3  RESET_N  IN  = PU_SPI0_RST
  4  NC(6)  NC  = TP_SPI_0_6
  5  NC(5)  NC  = TP_SPI_0_5
  6  NC(4)  NC  = TP_SPI_0_4
  7  CS_N  IN  = SPI_CS0_PRIMARY_R_N
  8  DO_IO(1)  BI  = SPI_MISO_R0
  9  WP_N_IO(2)  BI  = PU_BIOS_SPI_WP0_N
  10  GND  GROUND  = GND
  11  NC(3)  NC  = TP_SPI_0_3
  12  NC(2)  NC  = TP_SPI_0_2
  13  NC(1)  NC  = TP_SPI_0_1
  14  NC(0)  NC  = TP_SPI_0_0
  15  DI_IO(0)  BI  = SPI_SWITCH_MOSI_R0
  16  CLK  IN  = SPI_CLK_R0

U7W1  PI5A3157BC6E-GP  pkg DISCRET-GC2  page 166
  1  B1  UNSPEC  = PECI_BMC
  2  GND  POWER  = GND
  3  B0  UNSPEC  = PECI_PCH
  4  A  UNSPEC  = PECI_CPU_G
  5  VCC  POWER  = P3V3_STBY
  6  S  UNSPEC  = PECI_SEL

U8D2  TTL1G07_A  74LVC1G07 IC  pkg SOP  page 157 : 2 = PWRGD_DSW_PWROK ; 4 = RST_BMC_SRST_R2_N
U8D3  TTL1G07_A  74LVC1G07 IC  pkg SOP  page 170 : 2 = IRQ_SML1_PMBUS_ALERT_BUF_N ; 4 = IRQ_FORCE_NM_THROTTLE_R_N

U8D4  AT24C64  IC  pkg SOICLF  page 167
  1  A0  IN  = GND
  2  A1  IN  = GND
  3  A2  IN  = PU_AT24C64_A2
  5  SDA  BI  = SMB_SENSOR_STBY_LVC3_SDA_R2
  6  SCL  IN  = SMB_SENSOR_STBY_LVC3_SCL_R2
  7  WP  IN  = PD_FRU_WP

U8D5  TTL1G126_A  74HC1G126 IC  pkg SOT  page 170
  1  OE  IN  = FM_PMBUS_ALERT_BUF_EN
  2  A  IN  = IRQ_SML1_PMBUS_ALERT_N
  4  Y  OUT  = IRQ_SML1_PMBUS_ALERT_BUF_N
